(kicad_pcb
	(version 20241229)
	(generator "pcbnew")
	(generator_version "9.0")
	(general
		(thickness 1.711)
		(legacy_teardrops no)
	)
	(paper "A4")
	(title_block
		(title "Antmicro Baseboard for Jetson AGX Thor")
		(date "2026-02-18")
		(rev "1.1.0")
		(company "Antmicro Ltd")
		(comment 1 "www.antmicro.com")
		(comment 9 "footprints 1083-1085 of 1170")
	)
	(layers
		(0 "F.Cu" signal)
		(4 "In1.Cu" signal)
		(6 "In2.Cu" signal)
		(8 "In3.Cu" signal)
		(10 "In4.Cu" jumper)
		(12 "In5.Cu" signal)
		(14 "In6.Cu" signal)
		(16 "In7.Cu" signal)
		(18 "In8.Cu" signal)
		(2 "B.Cu" signal)
		(9 "F.Adhes" user "F.Adhesive")
		(11 "B.Adhes" user "B.Adhesive")
		(13 "F.Paste" user)
		(15 "B.Paste" user)
		(5 "F.SilkS" user "F.Silkscreen")
		(7 "B.SilkS" user "B.Silkscreen")
		(1 "F.Mask" user)
		(3 "B.Mask" user)
		(17 "Dwgs.User" user "User.Drawings")
		(19 "Cmts.User" user "User.Comments")
		(21 "Eco1.User" user "User.Eco1")
		(23 "Eco2.User" user "User.Eco2")
		(25 "Edge.Cuts" user)
		(27 "Margin" user)
		(31 "F.CrtYd" user "F.Courtyard")
		(29 "B.CrtYd" user "B.Courtyard")
		(35 "F.Fab" user)
		(33 "B.Fab" user)
	)
	(footprint "antmicro-footprints:LED_0603_1608Metric_G"
		(layer "B.Cu")
		(at 225.98 56.26 180)
		(descr "LED SMD 0603 Green")
		(tags "LED SMD 0603 Green")
		(property "Reference" "D27"
			(at -3.52 -0.44 0)
			(layer "B.SilkS")
			(effects
				(font
					(size 0.7 0.7)
					(thickness 0.15)
				)
				(justify left bottom mirror)
			)
		)
		(property "Value" "LED_G_0603_LTST-C190GKT"
			(at -0.001 -1.599 0)
			(layer "B.Fab")
			(effects
				(font
					(size 0.7 0.7)
					(thickness 0.15)
				)
				(justify left bottom mirror)
			)
		)
		(property "Datasheet" "https://media.digikey.com/pdf/Data%20Sheets/Lite-On%20PDFs/LTST-C190GKT.pdf"
			(at 0 0 0)
			(layer "B.Fab")
			(hide yes)
			(effects
				(font
					(size 1.27 1.27)
					(thickness 0.15)
				)
				(justify mirror)
			)
		)
		(property "Description" "LED, Green, SMD, 0603, 20 mA, 2.1 V, 569 nm"
			(at 0 0 0)
			(layer "B.Fab")
			(hide yes)
			(effects
				(font
					(size 1.27 1.27)
					(thickness 0.15)
				)
				(justify mirror)
			)
		)
		(property "MPN" "LTST-C190GKT"
			(at 0 0 0)
			(unlocked yes)
			(layer "B.Fab")
			(hide yes)
			(effects
				(font
					(size 1 1)
					(thickness 0.15)
				)
				(justify mirror)
			)
		)
		(property "Manufacturer" "Lite-On"
			(at 0 0 0)
			(unlocked yes)
			(layer "B.Fab")
			(hide yes)
			(effects
				(font
					(size 1 1)
					(thickness 0.15)
				)
				(justify mirror)
			)
		)
		(property "Author" "Antmicro"
			(at 0 0 0)
			(unlocked yes)
			(layer "B.Fab")
			(hide yes)
			(effects
				(font
					(size 1 1)
					(thickness 0.15)
				)
				(justify mirror)
			)
		)
		(property "License" "Apache-2.0"
			(at 0 0 0)
			(unlocked yes)
			(layer "B.Fab")
			(hide yes)
			(effects
				(font
					(size 1 1)
					(thickness 0.15)
				)
				(justify mirror)
			)
		)
		(property "Color" "Green"
			(at 0 0 0)
			(unlocked yes)
			(layer "B.Fab")
			(hide yes)
			(effects
				(font
					(size 1 1)
					(thickness 0.15)
				)
				(justify mirror)
			)
		)
		(sheetname "/CSI/")
		(sheetfile "csi.kicad_sch")
		(attr smd)
		(fp_line
			(start 0.22 0.35)
			(end -0.22 0.35)
			(stroke
				(width 0.15)
				(type solid)
			)
			(layer "B.SilkS")
		)
		(fp_line
			(start 0.22 -0.35)
			(end -0.22 -0.35)
			(stroke
				(width 0.15)
				(type solid)
			)
			(layer "B.SilkS")
		)
		(fp_line
			(start 0.105328 -0.001008)
			(end 0.240001 -0.001)
			(stroke
				(width 0.1)
				(type solid)
			)
			(layer "B.SilkS")
		)
		(fp_line
			(start 0.105328 -0.201008)
			(end 0.105329 0.198992)
			(stroke
				(width 0.1)
				(type solid)
			)
			(layer "B.SilkS")
		)
		(fp_line
			(start 0.105328 -0.201008)
			(end -0.094672 -0.001008)
			(stroke
				(width 0.1)
				(type solid)
			)
			(layer "B.SilkS")
		)
		(fp_line
			(start -0.094672 -0.001008)
			(end 0.105329 0.198992)
			(stroke
				(width 0.1)
				(type solid)
			)
			(layer "B.SilkS")
		)
		(fp_line
			(start -0.094672 -0.001008)
			(end -0.24 -0.001008)
			(stroke
				(width 0.1)
				(type solid)
			)
			(layer "B.SilkS")
		)
		(fp_line
			(start -0.094672 -0.201008)
			(end -0.094672 0.198992)
			(stroke
				(width 0.1)
				(type solid)
			)
			(layer "B.SilkS")
		)
		(fp_line
			(start -1.18 0.319)
			(end -1.18 -0.321)
			(stroke
				(width 0.15)
				(type solid)
			)
			(layer "B.SilkS")
		)
		(fp_poly
			(pts
				(xy 1.25 -0.65) (xy 1.25 0.65) (xy -1.25 0.65) (xy -1.25 -0.65)
			)
			(stroke
				(width 0.05)
				(type solid)
			)
			(fill no)
			(layer "B.CrtYd")
		)
		(fp_line
			(start 0.599 0)
			(end 0.200999 0)
			(stroke
				(width 0.15)
				(type solid)
			)
			(layer "B.Fab")
		)
		(fp_line
			(start 0.201 0.202)
			(end -0.101 0)
			(stroke
				(width 0.15)
				(type solid)
			)
			(layer "B.Fab")
		)
		(fp_line
			(start 0.201 -0.2)
			(end 0.200999 0)
			(stroke
				(width 0.15)
				(type solid)
			)
			(layer "B.Fab")
		)
		(fp_line
			(start 0.200999 0)
			(end 0.201 0.202)
			(stroke
				(width 0.15)
				(type solid)
			)
			(layer "B.Fab")
		)
		(fp_line
			(start -0.101 0)
			(end 0.201 -0.2)
			(stroke
				(width 0.15)
				(type solid)
			)
			(layer "B.Fab")
		)
		(fp_line
			(start -0.199 0.202)
			(end -0.199 -0.1)
			(stroke
				(width 0.15)
				(type solid)
			)
			(layer "B.Fab")
		)
		(fp_line
			(start -0.199 0)
			(end -0.597 0)
			(stroke
				(width 0.15)
				(type solid)
			)
			(layer "B.Fab")
		)
		(fp_line
			(start -0.199 -0.2)
			(end -0.199 -0.1)
			(stroke
				(width 0.15)
				(type solid)
			)
			(layer "B.Fab")
		)
		(fp_poly
			(pts
				(xy 0.848 -0.4) (xy 0.848 0.401999) (xy -0.85 0.402) (xy -0.85 -0.4)
			)
			(stroke
				(width 0.15)
				(type solid)
			)
			(fill no)
			(layer "B.Fab")
		)
		(fp_text user "License: Apache-2.0"
			(at -1.4224 -3.599 0)
			(layer "B.Fab")
			(effects
				(font
					(size 0.7 0.7)
					(thickness 0.15)
				)
				(justify left bottom mirror)
			)
		)
		(fp_text user "${REFERENCE}"
			(at -1.4224 -5.999 0)
			(layer "B.Fab")
			(effects
				(font
					(size 0.7 0.7)
					(thickness 0.15)
				)
				(justify left bottom mirror)
			)
		)
		(fp_text user "Author: Antmicro"
			(at -1.4224 -4.799 0)
			(layer "B.Fab")
			(effects
				(font
					(size 0.7 0.7)
					(thickness 0.15)
				)
				(justify left bottom mirror)
			)
		)
		(pad "1" smd roundrect
			(at -0.7 0)
			(size 0.8 1)
			(layers "B.Cu" "B.Mask" "B.Paste")
			(roundrect_rratio 0.2)
			(net 1 "GND")
			(pinfunction "C")
			(pintype "passive")
		)
		(pad "2" smd roundrect
			(at 0.7 0)
			(size 0.8 1)
			(layers "B.Cu" "B.Mask" "B.Paste")
			(roundrect_rratio 0.2)
			(net 540 "Net-(D27-A)")
			(pinfunction "A")
			(pintype "passive")
		)
	)
	(footprint "antmicro-footprints:SOT-523"
		(layer "B.Cu")
		(at 173.9 60.078004 -90)
		(property "Reference" "Q13"
			(at -1.078004 1.3 90)
			(layer "B.SilkS")
			(effects
				(font
					(size 0.7 0.7)
					(thickness 0.15)
				)
				(justify left bottom mirror)
			)
		)
		(property "Value" "DMG1012T-7"
			(at 0.1 -1.824 90)
			(layer "B.Fab")
			(effects
				(font
					(size 0.7 0.7)
					(thickness 0.15)
				)
				(justify left bottom mirror)
			)
		)
		(property "Datasheet" "https://www.diodes.com/assets/Datasheets/ds31783.pdf"
			(at 0 0 90)
			(layer "B.Fab")
			(hide yes)
			(effects
				(font
					(size 1.27 1.27)
					(thickness 0.15)
				)
				(justify mirror)
			)
		)
		(property "Description" "Power MOSFET, N Channel, 20 V, 630 mA, 0.3 ohm, SOT-523, Surface Mount"
			(at 0 0 90)
			(layer "B.Fab")
			(hide yes)
			(effects
				(font
					(size 1.27 1.27)
					(thickness 0.15)
				)
				(justify mirror)
			)
		)
		(property "MPN" "DMG1012T-7"
			(at 0 0 90)
			(unlocked yes)
			(layer "B.Fab")
			(hide yes)
			(effects
				(font
					(size 1 1)
					(thickness 0.15)
				)
				(justify mirror)
			)
		)
		(property "Manufacturer" "Diodes Incorporated"
			(at 0 0 90)
			(unlocked yes)
			(layer "B.Fab")
			(hide yes)
			(effects
				(font
					(size 1 1)
					(thickness 0.15)
				)
				(justify mirror)
			)
		)
		(property "Author" "Antmicro"
			(at 0 0 90)
			(unlocked yes)
			(layer "B.Fab")
			(hide yes)
			(effects
				(font
					(size 1 1)
					(thickness 0.15)
				)
				(justify mirror)
			)
		)
		(property "License" "Apache-2.0"
			(at 0 0 90)
			(unlocked yes)
			(layer "B.Fab")
			(hide yes)
			(effects
				(font
					(size 1 1)
					(thickness 0.15)
				)
				(justify mirror)
			)
		)
		(sheetname "/Peripherals/")
		(sheetfile "peripherals.kicad_sch")
		(attr smd)
		(fp_line
			(start -0.725 0.551)
			(end -0.277 0.551)
			(stroke
				(width 0.15)
				(type solid)
			)
			(layer "B.SilkS")
		)
		(fp_line
			(start -0.277 0.551)
			(end -0.277 0.75)
			(stroke
				(width 0.15)
				(type solid)
			)
			(layer "B.SilkS")
		)
		(fp_line
			(start -0.927 0.351)
			(end -0.725 0.551)
			(stroke
				(width 0.15)
				(type solid)
			)
			(layer "B.SilkS")
		)
		(fp_line
			(start -0.927 0.051)
			(end -0.927 0.351)
			(stroke
				(width 0.15)
				(type solid)
			)
			(layer "B.SilkS")
		)
		(fp_circle
			(center -0.9652 -0.9652)
			(end -0.9152 -0.9652)
			(stroke
				(width 0.15)
				(type solid)
			)
			(fill yes)
			(layer "B.SilkS")
		)
		(fp_line
			(start -1.12 1.16)
			(end 1.1 1.16)
			(stroke
				(width 0.05)
				(type solid)
			)
			(layer "B.CrtYd")
		)
		(fp_line
			(start -1.12 1.16)
			(end -1.12 -1.15)
			(stroke
				(width 0.05)
				(type solid)
			)
			(layer "B.CrtYd")
		)
		(fp_line
			(start 1.1 1.16)
			(end 1.1 -1.15)
			(stroke
				(width 0.05)
				(type solid)
			)
			(layer "B.CrtYd")
		)
		(fp_line
			(start -1.12 -1.15)
			(end 1.1 -1.15)
			(stroke
				(width 0.05)
				(type solid)
			)
			(layer "B.CrtYd")
		)
		(fp_line
			(start -0.652 0.425)
			(end -0.802 0.276)
			(stroke
				(width 0.15)
				(type solid)
			)
			(layer "B.Fab")
		)
		(fp_line
			(start 0.8 0.425)
			(end -0.652 0.425)
			(stroke
				(width 0.15)
				(type solid)
			)
			(layer "B.Fab")
		)
		(fp_line
			(start 0.8 0.425)
			(end 0.8 -0.424)
			(stroke
				(width 0.15)
				(type solid)
			)
			(layer "B.Fab")
		)
		(fp_line
			(start -0.802 0.276)
			(end -0.802 -0.424)
			(stroke
				(width 0.15)
				(type solid)
			)
			(layer "B.Fab")
		)
		(fp_line
			(start 0.8 -0.424)
			(end -0.802 -0.424)
			(stroke
				(width 0.15)
				(type solid)
			)
			(layer "B.Fab")
		)
		(fp_circle
			(center -0.9652 -0.9652)
			(end -0.9144 -0.9652)
			(stroke
				(width 0.15)
				(type solid)
			)
			(fill no)
			(layer "B.Fab")
		)
		(fp_text user "License: Apache-2.0"
			(at -1.12 -5.024 90)
			(layer "B.Fab")
			(effects
				(font
					(size 0.7 0.7)
					(thickness 0.15)
				)
				(justify left bottom mirror)
			)
		)
		(fp_text user "Author: Antmicro"
			(at -1.12 -6.224 90)
			(layer "B.Fab")
			(effects
				(font
					(size 0.7 0.7)
					(thickness 0.15)
				)
				(justify left bottom mirror)
			)
		)
		(fp_text user "${REFERENCE}"
			(at -1.12 -3.824 90)
			(layer "B.Fab")
			(effects
				(font
					(size 0.7 0.7)
					(thickness 0.15)
				)
				(justify left bottom mirror)
			)
		)
		(pad "1" smd rect
			(at -0.5 -0.65 270)
			(size 0.4 0.51)
			(layers "B.Cu" "B.Mask" "B.Paste")
			(net 487 "/Expansion connector/GPIO.USER_LED0")
			(pinfunction "G")
			(pintype "input")
		)
		(pad "2" smd rect
			(at 0.498 -0.65 270)
			(size 0.4 0.51)
			(layers "B.Cu" "B.Mask" "B.Paste")
			(net 1 "GND")
			(pinfunction "S")
			(pintype "passive")
		)
		(pad "3" smd rect
			(at 0 0.652 270)
			(size 0.4 0.51)
			(layers "B.Cu" "B.Mask" "B.Paste")
			(net 37 "Net-(D35-C)")
			(pinfunction "D")
			(pintype "passive")
		)
	)
	(footprint "antmicro-footprints:SOD-523"
		(layer "B.Cu")
		(at 216.02 113.56 90)
		(property "Reference" "D58"
			(at -1.14 -1.52 90)
			(layer "B.SilkS")
			(effects
				(font
					(size 0.7 0.7)
					(thickness 0.15)
				)
				(justify right top mirror)
			)
		)
		(property "Value" "RB521S30T1G"
			(at 0 -1.499 90)
			(layer "B.Fab")
			(effects
				(font
					(size 0.7 0.7)
					(thickness 0.15)
				)
				(justify right top mirror)
			)
		)
		(property "Datasheet" "https://www.onsemi.com/pdf/datasheet/rb521s30t1-d.pdf"
			(at 0 0 90)
			(layer "B.Fab")
			(hide yes)
			(effects
				(font
					(size 1.27 1.27)
					(thickness 0.15)
				)
				(justify mirror)
			)
		)
		(property "Description" "Small Signal Schottky Diode, Single, 30 V, 200 mA, 500 mV, 1 A, 125 °C"
			(at 0 0 90)
			(layer "B.Fab")
			(hide yes)
			(effects
				(font
					(size 1.27 1.27)
					(thickness 0.15)
				)
				(justify mirror)
			)
		)
		(property "MPN" "RB521S30T1G"
			(at 0 0 270)
			(unlocked yes)
			(layer "B.Fab")
			(hide yes)
			(effects
				(font
					(size 1 1)
					(thickness 0.15)
				)
				(justify mirror)
			)
		)
		(property "Manufacturer" "ON Semiconductor"
			(at 0 0 270)
			(unlocked yes)
			(layer "B.Fab")
			(hide yes)
			(effects
				(font
					(size 1 1)
					(thickness 0.15)
				)
				(justify mirror)
			)
		)
		(property "Author" "Antmicro"
			(at 0 0 270)
			(unlocked yes)
			(layer "B.Fab")
			(hide yes)
			(effects
				(font
					(size 1 1)
					(thickness 0.15)
				)
				(justify mirror)
			)
		)
		(property "License" "Apache-2.0"
			(at 0 0 270)
			(unlocked yes)
			(layer "B.Fab")
			(hide yes)
			(effects
				(font
					(size 1 1)
					(thickness 0.15)
				)
				(justify mirror)
			)
		)
		(sheetname "/USB Hub/")
		(sheetfile "usb_hub.kicad_sch")
		(attr smd)
		(fp_line
			(start -0.35 0.5)
			(end -0.35 -0.5)
			(stroke
				(width 0.15)
				(type solid)
			)
			(layer "B.SilkS")
		)
		(fp_rect
			(start -1 0.6)
			(end 1 -0.6)
			(stroke
				(width 0.05)
				(type solid)
			)
			(fill no)
			(layer "B.CrtYd")
		)
		(fp_line
			(start -0.652 -0.423)
			(end 0.65 -0.423)
			(stroke
				(width 0.15)
				(type solid)
			)
			(layer "B.Fab")
		)
		(fp_line
			(start -0.652 -0.423)
			(end -0.652 0.425)
			(stroke
				(width 0.15)
				(type solid)
			)
			(layer "B.Fab")
		)
		(fp_line
			(start -0.35 0.4)
			(end -0.35 -0.4)
			(stroke
				(width 0.15)
				(type solid)
			)
			(layer "B.Fab")
		)
		(fp_line
			(start 0.65 0.425)
			(end 0.65 -0.423)
			(stroke
				(width 0.15)
				(type solid)
			)
			(layer "B.Fab")
		)
		(fp_line
			(start -0.652 0.425)
			(end 0.65 0.425)
			(stroke
				(width 0.15)
				(type solid)
			)
			(layer "B.Fab")
		)
		(fp_text user "Author: Antmicro"
			(at -1.276 -4.7 90)
			(layer "B.Fab")
			(effects
				(font
					(size 0.7 0.7)
					(thickness 0.15)
				)
				(justify right top mirror)
			)
		)
		(fp_text user "License: Apache-2.0"
			(at -1.276 -5.9 90)
			(layer "B.Fab")
			(effects
				(font
					(size 0.7 0.7)
					(thickness 0.15)
				)
				(justify right top mirror)
			)
		)
		(fp_text user "${REFERENCE}"
			(at -1.276 -3.499 90)
			(layer "B.Fab")
			(effects
				(font
					(size 0.7 0.7)
					(thickness 0.15)
				)
				(justify right top mirror)
			)
		)
		(pad "1" smd roundrect
			(at -0.701 0 90)
			(size 0.5 0.6)
			(layers "B.Cu" "B.Mask" "B.Paste")
			(roundrect_rratio 0.25)
			(net 1237 "Net-(D58-C)")
			(pinfunction "C")
			(pintype "passive")
		)
		(pad "2" smd roundrect
			(at 0.699 0 90)
			(size 0.5 0.6)
			(layers "B.Cu" "B.Mask" "B.Paste")
			(roundrect_rratio 0.25)
			(net 1236 "Net-(D58-A)")
			(pinfunction "A")
			(pintype "passive")
		)
	)
)
